(kicad_pcb
	(version 20221018)
	(generator pcbnew)
	(general
    (thickness 0.908)
  )
	(paper "A4")
	(title_block
    (title "HDMI-MIPI Bridge")
    (date "2024-04-24")
    (rev "1.3.2")
		(comment 9 "footprints 56-62 of 121")
	)
	(layers
    (0 "F.Cu" signal)
    (1 "In1.Cu" signal)
    (2 "In2.Cu" signal)
    (31 "B.Cu" signal)
    (32 "B.Adhes" user "B.Adhesive")
    (33 "F.Adhes" user "F.Adhesive")
    (34 "B.Paste" user)
    (35 "F.Paste" user)
    (36 "B.SilkS" user "B.Silkscreen")
    (37 "F.SilkS" user "F.Silkscreen")
    (38 "B.Mask" user)
    (39 "F.Mask" user)
    (40 "Dwgs.User" user "User.Drawings")
    (41 "Cmts.User" user "User.Comments")
    (42 "Eco1.User" user "User.Eco1")
    (43 "Eco2.User" user "User.Eco2")
    (44 "Edge.Cuts" user)
    (45 "Margin" user)
    (46 "B.CrtYd" user "B.Courtyard")
    (47 "F.CrtYd" user "F.Courtyard")
    (48 "B.Fab" user)
    (49 "F.Fab" user)
  )
	(footprint "antmicro-footprints:SOT-23-5" (layer "F.Cu")
    (at 143.95 119.1 90)
    (property "Author" "Antmicro")
    (property "License" "Apache-2.0")
    (property "MPN" "TLV73312PDBVT")
    (property "Manufacturer" "Texas Instruments")
    (property "Sheetfile" "channel1.kicad_sch")
    (property "Sheetname" "Channel 1")
    (property "ki_description" "Fixed LDO Voltage Regulator, 1.4V to 5.5V, 122mV Dropout, 1.2Vout, 300mAout, SOT-23-5")
    (property "ki_keywords" "SMT, PMIC, IC, LDO, LINEAR, VOLTAGE, REGULATOR")
    (attr smd)
    (fp_text reference "IC2" (at -2.89 -0.9 180) (layer "F.SilkS")
        (effects (font (size 0.65 0.65) (thickness 0.13)) (justify left bottom))
    )
    (fp_text value "TLV73312PDBVT" (at 0.002 2.799 90) (layer "F.Fab")
        (effects (font (size 0.65 0.65) (thickness 0.13)) (justify left bottom))
    )
    (fp_text user "Author: Antmicro" (at -1.898 5.499 90) (layer "F.Fab") hide
        (effects (font (size 0.7 0.7) (thickness 0.15)) (justify left bottom))
    )
    (fp_text user "${REFERENCE}" (at -1.898 4.299 90) (layer "F.Fab") hide
        (effects (font (size 0.7 0.7) (thickness 0.15)) (justify left bottom))
    )
    (fp_text user "License: Apache-2.0" (at -1.898 6.7 90) (layer "F.Fab") hide
        (effects (font (size 0.7 0.7) (thickness 0.15)) (justify left bottom))
    )
    (fp_line (start -0.85 1.6) (end -0.85 1.301)
      (stroke (width 0.15) (type solid)) (layer "F.SilkS"))
    (fp_line (start -0.8 -1.6) (end -0.8 -1.3)
      (stroke (width 0.15) (type solid)) (layer "F.SilkS"))
    (fp_line (start -0.8 -1.6) (end -0.5 -1.6)
      (stroke (width 0.15) (type solid)) (layer "F.SilkS"))
    (fp_line (start -0.55 1.6) (end -0.85 1.6)
      (stroke (width 0.15) (type solid)) (layer "F.SilkS"))
    (fp_line (start 0.8 -1.6) (end 0.5 -1.6)
      (stroke (width 0.15) (type solid)) (layer "F.SilkS"))
    (fp_line (start 0.8 -1.3) (end 0.8 -1.6)
      (stroke (width 0.15) (type solid)) (layer "F.SilkS"))
    (fp_line (start 0.8 0.55) (end 0.8 -0.55)
      (stroke (width 0.15) (type solid)) (layer "F.SilkS"))
    (fp_line (start 0.8 1.3) (end 0.8 1.599)
      (stroke (width 0.15) (type solid)) (layer "F.SilkS"))
    (fp_line (start 0.8 1.599) (end 0.549 1.599)
      (stroke (width 0.15) (type solid)) (layer "F.SilkS"))
    (fp_circle (center -1.25 -1.5) (end -1.2 -1.5)
      (stroke (width 0.15) (type solid)) (fill solid) (layer "F.SilkS"))
    (fp_rect (start 1.9 -1.76) (end -1.9 1.75)
      (stroke (width 0.05) (type solid)) (fill none) (layer "F.CrtYd"))
    (fp_line (start -0.398 -1.526) (end -0.874 -1.05)
      (stroke (width 0.15) (type solid)) (layer "F.Fab"))
    (fp_rect (start 0.874 1.523) (end -0.873 -1.525)
      (stroke (width 0.15) (type solid)) (fill none) (layer "F.Fab"))
    (pad "1" smd rect (at -1.351 -0.951) (size 0.55 1) (layers "F.Cu" "F.Paste" "F.Mask")
      (net 9 "+3V3") (pinfunction "VIN") (pintype "power_in"))
    (pad "2" smd rect (at -1.351 0) (size 0.55 1) (layers "F.Cu" "F.Paste" "F.Mask")
      (net 2 "GND") (pinfunction "GND") (pintype "power_in"))
    (pad "3" smd rect (at -1.351 0.949) (size 0.55 1) (layers "F.Cu" "F.Paste" "F.Mask")
      (net 9 "+3V3") (pinfunction "EN") (pintype "input"))
    (pad "4" smd rect (at 1.35 0.949) (size 0.55 1) (layers "F.Cu" "F.Paste" "F.Mask")
      (net 101 "unconnected-(IC2-NC-Pad4)") (pinfunction "NC") (pintype "no_connect"))
    (pad "5" smd rect (at 1.35 -0.951) (size 0.55 1) (layers "F.Cu" "F.Paste" "F.Mask")
      (net 12 "CH1_1V2") (pinfunction "VOUT") (pintype "power_out"))
  )
	(footprint "antmicro-footprints:C_0402_1005Metric" (layer "F.Cu")
    (at 131 108.4 180)
    (descr "Capacitor SMD 0402")
    (tags "capacitor SMD 0402")
    (property "Author" "Antmicro")
    (property "Dielectric" "")
    (property "License" "Apache-2.0")
    (property "MPN" "0402B471K250CT")
    (property "Manufacturer" "Walsin")
    (property "Public" "False")
    (property "Sheetfile" "channel1.kicad_sch")
    (property "Sheetname" "Channel 1")
    (property "Val" "470p")
    (property "Voltage" "")
    (property "ki_description" "SMD Multilayer Ceramic Capacitor, General Purpose, 470 pF, 25 V, 0402 [1005 Metric], ± 10%, X7R")
    (property "ki_keywords" "0402, SMT, CAPACITOR, PASSIVE, MLCC")
    (attr smd)
    (fp_text reference "C7" (at 0.1 -7.6) (layer "F.SilkS")
        (effects (font (size 0.65 0.65) (thickness 0.13)) (justify right bottom))
    )
    (fp_text value "C_470p_0402" (at 0 1.4) (layer "F.Fab")
        (effects (font (size 0.65 0.65) (thickness 0.13)) (justify right bottom))
    )
    (fp_text user "License: Apache-2.0" (at -0.932 5.17) (layer "F.Fab") hide
        (effects (font (size 0.7 0.7) (thickness 0.15)) (justify right bottom))
    )
    (fp_text user "Author: Antmicro" (at -0.932 4.17) (layer "F.Fab") hide
        (effects (font (size 0.7 0.7) (thickness 0.15)) (justify right bottom))
    )
    (fp_text user "${REFERENCE}" (at -0.932 3.168) (layer "F.Fab") hide
        (effects (font (size 0.7 0.7) (thickness 0.15)) (justify right bottom))
    )
    (fp_rect (start -0.925 -0.47) (end 0.925 0.47)
      (stroke (width 0.05) (type default)) (fill none) (layer "F.CrtYd"))
    (fp_line (start -0.494 -0.25) (end 0.504 -0.25)
      (stroke (width 0.15) (type solid)) (layer "F.Fab"))
    (fp_line (start -0.494 0.248) (end -0.494 -0.25)
      (stroke (width 0.15) (type solid)) (layer "F.Fab"))
    (fp_line (start 0.504 -0.25) (end 0.504 0.248)
      (stroke (width 0.15) (type solid)) (layer "F.Fab"))
    (fp_line (start 0.504 0.248) (end -0.494 0.248)
      (stroke (width 0.15) (type solid)) (layer "F.Fab"))
    (pad "1" smd roundrect (at -0.48 0 180) (size 0.59 0.64) (layers "F.Cu" "F.Paste" "F.Mask") (roundrect_rratio 0.25)
      (net 8 "Net-(U1B-VDDC1)") (pintype "passive"))
    (pad "2" smd roundrect (at 0.48 0 180) (size 0.59 0.64) (layers "F.Cu" "F.Paste" "F.Mask") (roundrect_rratio 0.25)
      (net 2 "GND") (pintype "passive"))
  )
	(footprint "antmicro-footprints:R_0402_1005Metric" (layer "F.Cu")
    (at 169.15 107.95 -90)
    (descr "Resistor SMD 0402")
    (tags "resistor SMD 0402")
    (property "Author" "Antmicro")
    (property "License" "Apache-2.0")
    (property "MPN" "CR0402-FX-1002GLF")
    (property "Manufacturer" "Bourns")
    (property "Public" "False")
    (property "Sheetfile" "channel2.kicad_sch")
    (property "Sheetname" "Channel 2")
    (property "Tolerance" "1%")
    (property "Val" "10k")
    (property "ki_description" "SMD Chip Resistor, 10 kohm, ± 1%, 62.5 mW, 0402 [1005 Metric], Thick Film, General Purpose")
    (property "ki_keywords" "0402, SMT, RESISTOR, PASSIVE")
    (attr smd)
    (fp_text reference "R22" (at 1.11 -2.37 -90) (layer "F.SilkS")
        (effects (font (size 0.65 0.65) (thickness 0.13)) (justify left bottom))
    )
    (fp_text value "R_10k_0402" (at 0 1.4 -90) (layer "F.Fab")
        (effects (font (size 0.65 0.65) (thickness 0.13)) (justify left bottom))
    )
    (fp_text user "License: Apache-2.0" (at -0.95 5.169 -90) (layer "F.Fab") hide
        (effects (font (size 0.7 0.7) (thickness 0.15)) (justify left bottom))
    )
    (fp_text user "${REFERENCE}" (at -0.95 3.168 -90) (layer "F.Fab") hide
        (effects (font (size 0.7 0.7) (thickness 0.15)) (justify left bottom))
    )
    (fp_text user "Author: Antmicro" (at -0.95 4.169 -90) (layer "F.Fab") hide
        (effects (font (size 0.7 0.7) (thickness 0.15)) (justify left bottom))
    )
    (fp_rect (start -0.925 -0.47) (end 0.925 0.47)
      (stroke (width 0.05) (type default)) (fill none) (layer "F.CrtYd"))
    (fp_rect (start -0.5 -0.25) (end 0.5 0.25)
      (stroke (width 0.15) (type solid)) (fill none) (layer "F.Fab"))
    (pad "1" smd roundrect (at -0.48 0 270) (size 0.59 0.64) (layers "F.Cu" "F.Paste" "F.Mask") (roundrect_rratio 0.25)
      (net 111 "/Channel 2/HDMI2_DDC_SDA_3V3") (pintype "passive"))
    (pad "2" smd roundrect (at 0.48 0 270) (size 0.59 0.64) (layers "F.Cu" "F.Paste" "F.Mask") (roundrect_rratio 0.25)
      (net 9 "+3V3") (pintype "passive"))
  )
	(footprint "antmicro-footprints:C_0603_1608Metric" (layer "F.Cu")
    (at 130.6 107.2)
    (descr "Capacitor SMD 0603")
    (tags "capacitor 0603")
    (property "Author" "Antmicro")
    (property "Dielectric" "")
    (property "License" "Apache-2.0")
    (property "MPN" "C1608X5R1V475M080AC")
    (property "Manufacturer" "TDK")
    (property "Public" "False")
    (property "Sheetfile" "channel1.kicad_sch")
    (property "Sheetname" "Channel 1")
    (property "Val" "4u7")
    (property "Voltage" "")
    (property "ki_description" "SMD Multilayer Ceramic Capacitor, 4.7 µF, 35 V, 0603 [1608 Metric], ± 20%, X5R, C")
    (property "ki_keywords" "0603, SMT, CAPACITOR, PASSIVE, CERAMIC, MLCC")
    (attr smd)
    (fp_text reference "C11" (at -3.25 -0.1) (layer "F.SilkS")
        (effects (font (size 0.65 0.65) (thickness 0.13)) (justify left bottom))
    )
    (fp_text value "C_4u7_0603" (at 0 1.6) (layer "F.Fab")
        (effects (font (size 0.65 0.65) (thickness 0.13)) (justify left bottom))
    )
    (fp_text user "Author: Antmicro" (at -1.682 4.894) (layer "F.Fab") hide
        (effects (font (size 0.7 0.7) (thickness 0.15)) (justify left bottom))
    )
    (fp_text user "License: Apache-2.0" (at -1.682 5.895) (layer "F.Fab") hide
        (effects (font (size 0.7 0.7) (thickness 0.15)) (justify left bottom))
    )
    (fp_text user "${REFERENCE}" (at -1.682 3.895) (layer "F.Fab") hide
        (effects (font (size 0.7 0.7) (thickness 0.15)) (justify left bottom))
    )
    (fp_line (start -0.15 -0.4) (end 0.15 -0.4)
      (stroke (width 0.15) (type solid)) (layer "F.SilkS"))
    (fp_line (start -0.15 0.4) (end 0.15 0.4)
      (stroke (width 0.15) (type solid)) (layer "F.SilkS"))
    (fp_rect (start -1.25 -0.65) (end 1.25 0.65)
      (stroke (width 0.05) (type solid)) (fill none) (layer "F.CrtYd"))
    (fp_rect (start -0.8 -0.4) (end 0.8 0.4)
      (stroke (width 0.15) (type solid)) (fill none) (layer "F.Fab"))
    (pad "1" smd roundrect (at -0.7 0) (size 0.8 1) (layers "F.Cu" "F.Paste" "F.Mask") (roundrect_rratio 0.2)
      (net 2 "GND") (pintype "passive"))
    (pad "2" smd roundrect (at 0.7 0) (size 0.8 1) (layers "F.Cu" "F.Paste" "F.Mask") (roundrect_rratio 0.2)
      (net 8 "Net-(U1B-VDDC1)") (pintype "passive"))
  )
	(footprint "antmicro-footprints:R-PDSO-N15" (layer "F.Cu")
    (at 135.25 103.37 90)
    (property "Author" "Antmicro")
    (property "License" "Apache-2.0")
    (property "MPN" "TPD8S009DSMR")
    (property "Manufacturer" "Texas Instruments")
    (property "Sheetfile" "channel1.kicad_sch")
    (property "Sheetname" "Channel 1")
    (property "ki_description" "TVS diode array, 8 kV, R-PDSO-N15, 5.5 V, 0.8 pF")
    (property "ki_keywords" "SMT, DIODE, SEMICONDUCTOR, TVS, ESD")
    (attr smd)
    (fp_text reference "U2" (at -0.43 -3.65 90) (layer "F.SilkS")
        (effects (font (size 0.65 0.65) (thickness 0.13)) (justify left bottom))
    )
    (fp_text value "TPD8S009DSMR" (at 0 4.4 90) (layer "F.Fab")
        (effects (font (size 0.65 0.65) (thickness 0.13)) (justify left bottom))
    )
    (fp_text user "License: Apache-2.0" (at -4.1 6.15 90) (layer "F.Fab") hide
        (effects (font (size 0.7 0.7) (thickness 0.15)) (justify left bottom))
    )
    (fp_text user "${REFERENCE}" (at -4.1 4.95 90) (layer "F.Fab") hide
        (effects (font (size 0.7 0.7) (thickness 0.15)) (justify left bottom))
    )
    (fp_text user "Author: Antmicro" (at -4.1 7.35 90) (layer "F.Fab") hide
        (effects (font (size 0.7 0.7) (thickness 0.15)) (justify left bottom))
    )
    (fp_circle (center -1.6 -3.2) (end -1.6 -3.15)
      (stroke (width 0.15) (type solid)) (fill solid) (layer "F.SilkS"))
    (fp_rect (start 1.8 -3.5) (end -1.89 3.49)
      (stroke (width 0.05) (type solid)) (fill none) (layer "F.CrtYd"))
    (fp_line (start -1.3 -3.051) (end -1.1 -3.25)
      (stroke (width 0.15) (type solid)) (layer "F.Fab"))
    (fp_rect (start 1.301 -3.25) (end -1.3 3.249)
      (stroke (width 0.15) (type solid)) (fill none) (layer "F.Fab"))
    (pad "1" smd roundrect (at -0.95 -2.75) (size 0.3 1.45) (layers "F.Cu" "F.Paste" "F.Mask") (roundrect_rratio 0.25)
      (net 74 "/Channel 1/HDMI1_D2_P") (pinfunction "D0+") (pintype "passive"))
    (pad "2" smd roundrect (at -0.95 -2.25) (size 0.3 1.45) (layers "F.Cu" "F.Paste" "F.Mask") (roundrect_rratio 0.25)
      (net 2 "GND") (pinfunction "GND") (pintype "passive"))
    (pad "3" smd roundrect (at -0.95 -1.75) (size 0.3 1.45) (layers "F.Cu" "F.Paste" "F.Mask") (roundrect_rratio 0.25)
      (net 75 "/Channel 1/HDMI1_D2_N") (pinfunction "D0-") (pintype "passive"))
    (pad "4" smd roundrect (at -0.95 -1.25) (size 0.3 1.45) (layers "F.Cu" "F.Paste" "F.Mask") (roundrect_rratio 0.25)
      (net 76 "/Channel 1/HDMI1_D1_P") (pinfunction "D1+") (pintype "passive"))
    (pad "5" smd roundrect (at -0.95 -0.75) (size 0.3 1.45) (layers "F.Cu" "F.Paste" "F.Mask") (roundrect_rratio 0.25)
      (net 2 "GND") (pinfunction "GND") (pintype "passive"))
    (pad "6" smd roundrect (at -0.95 -0.25) (size 0.3 1.45) (layers "F.Cu" "F.Paste" "F.Mask") (roundrect_rratio 0.25)
      (net 77 "/Channel 1/HDMI1_D1_N") (pinfunction "D1-") (pintype "passive"))
    (pad "7" smd roundrect (at -0.95 0.247) (size 0.3 1.45) (layers "F.Cu" "F.Paste" "F.Mask") (roundrect_rratio 0.25)
      (net 78 "/Channel 1/HDMI1_D0_P") (pinfunction "D2+") (pintype "passive"))
    (pad "8" smd roundrect (at -0.95 0.747) (size 0.3 1.45) (layers "F.Cu" "F.Paste" "F.Mask") (roundrect_rratio 0.25)
      (net 2 "GND") (pinfunction "GND") (pintype "passive"))
    (pad "9" smd roundrect (at -0.95 1.249) (size 0.3 1.45) (layers "F.Cu" "F.Paste" "F.Mask") (roundrect_rratio 0.25)
      (net 79 "/Channel 1/HDMI1_D0_N") (pinfunction "D2-") (pintype "passive"))
    (pad "10" smd roundrect (at -0.95 1.749) (size 0.3 1.45) (layers "F.Cu" "F.Paste" "F.Mask") (roundrect_rratio 0.25)
      (net 80 "/Channel 1/HDMI1_CLK_P") (pinfunction "D3+") (pintype "passive"))
    (pad "11" smd roundrect (at -0.95 2.249) (size 0.3 1.45) (layers "F.Cu" "F.Paste" "F.Mask") (roundrect_rratio 0.25)
      (net 2 "GND") (pinfunction "GND") (pintype "passive"))
    (pad "12" smd roundrect (at -0.95 2.749) (size 0.3 1.45) (layers "F.Cu" "F.Paste" "F.Mask") (roundrect_rratio 0.25)
      (net 81 "/Channel 1/HDMI1_CLK_N") (pinfunction "D3-") (pintype "passive"))
    (pad "13" smd roundrect (at 0.901 1.499) (size 0.3 1.45) (layers "F.Cu" "F.Paste" "F.Mask") (roundrect_rratio 0.25)
      (net 9 "+3V3") (pinfunction "VCC") (pintype "power_in"))
    (pad "14" smd roundrect (at 0.901 0) (size 0.3 1.45) (layers "F.Cu" "F.Paste" "F.Mask") (roundrect_rratio 0.25)
      (net 130 "unconnected-(U2-NC-Pad14)") (pinfunction "NC") (pintype "no_connect"))
    (pad "15" smd roundrect (at 0.901 -1.5) (size 0.3 1.45) (layers "F.Cu" "F.Paste" "F.Mask") (roundrect_rratio 0.25)
      (net 9 "+3V3") (pinfunction "VCC") (pintype "passive"))
  )
	(footprint "antmicro-footprints:FB_0603_1608Metric" (layer "F.Cu")
    (at 146.2 99.8 90)
    (property "Author" "Antmicro")
    (property "Current" "")
    (property "License" "Apache-2.0")
    (property "MPN" "BLM18SG121TN1D")
    (property "Manufacturer" "Murata")
    (property "Public" "False")
    (property "Sheetfile" "channel1.kicad_sch")
    (property "Sheetname" "Channel 1")
    (property "Val" "120Z/3A")
    (property "ki_description" "Ferrite Bead, 0603 [1608 Metric], 120 ohm, 3 A, BLM18S, 0.025 ohm, ± 25%, DC power line (thin type) ")
    (property "ki_keywords" "0603, SMT, FERRITE BEAD, PASSIVE")
    (attr smd)
    (fp_text reference "FB1" (at -1.15 1.57 90) (layer "F.SilkS")
        (effects (font (size 0.65 0.65) (thickness 0.13)) (justify left bottom))
    )
    (fp_text value "FB_120Z_3A_Murata-BLM18SG_0603" (at 0 1.5 90) (layer "F.Fab")
        (effects (font (size 0.65 0.65) (thickness 0.13)) (justify left bottom))
    )
    (fp_text user "License: Apache-2.0" (at -1.653 5.9 90) (layer "F.Fab") hide
        (effects (font (size 0.7 0.7) (thickness 0.15)) (justify left bottom))
    )
    (fp_text user "Author: Antmicro" (at -1.653 3.162 90) (layer "F.Fab") hide
        (effects (font (size 0.7 0.7) (thickness 0.15)) (justify left bottom))
    )
    (fp_text user "${REFERENCE}" (at -1.653 4.6 90) (layer "F.Fab") hide
        (effects (font (size 0.7 0.7) (thickness 0.15)) (justify left bottom))
    )
    (fp_line (start -0.15 -0.4) (end 0.15 -0.4)
      (stroke (width 0.15) (type solid)) (layer "F.SilkS"))
    (fp_line (start -0.15 0.4) (end 0.15 0.4)
      (stroke (width 0.15) (type solid)) (layer "F.SilkS"))
    (fp_rect (start -1.25 -0.65) (end 1.25 0.65)
      (stroke (width 0.05) (type solid)) (fill none) (layer "F.CrtYd"))
    (fp_line (start -0.803 0.406) (end -0.803 -0.408)
      (stroke (width 0.15) (type solid)) (layer "F.Fab"))
    (fp_line (start 0.8 -0.408) (end -0.803 -0.408)
      (stroke (width 0.15) (type solid)) (layer "F.Fab"))
    (fp_line (start 0.8 -0.408) (end 0.8 0.406)
      (stroke (width 0.15) (type solid)) (layer "F.Fab"))
    (fp_line (start 0.8 0.406) (end -0.803 0.406)
      (stroke (width 0.15) (type solid)) (layer "F.Fab"))
    (pad "1" smd roundrect (at -0.7 0 90) (size 0.8 1) (layers "F.Cu" "F.Paste" "F.Mask") (roundrect_rratio 0.2)
      (net 2 "GND") (pintype "passive"))
    (pad "2" smd roundrect (at 0.7 0 90) (size 0.8 1) (layers "F.Cu" "F.Paste" "F.Mask") (roundrect_rratio 0.2)
      (net 28 "Net-(FB1-Pad2)") (pintype "passive"))
  )
	(footprint "antmicro-footprints:C_0603_1608Metric" (layer "F.Cu")
    (at 164.11 109.53 180)
    (descr "Capacitor SMD 0603")
    (tags "capacitor 0603")
    (property "Author" "Antmicro")
    (property "Dielectric" "")
    (property "License" "Apache-2.0")
    (property "MPN" "C1608X5R1V475M080AC")
    (property "Manufacturer" "TDK")
    (property "Public" "False")
    (property "Sheetfile" "channel2.kicad_sch")
    (property "Sheetname" "Channel 2")
    (property "Val" "4u7")
    (property "Voltage" "")
    (property "ki_description" "SMD Multilayer Ceramic Capacitor, 4.7 µF, 35 V, 0603 [1608 Metric], ± 20%, X5R, C")
    (property "ki_keywords" "0603, SMT, CAPACITOR, PASSIVE, CERAMIC, MLCC")
    (attr smd)
    (fp_text reference "C51" (at 1.9 -6.95) (layer "F.SilkS")
        (effects (font (size 0.65 0.65) (thickness 0.13)) (justify right bottom))
    )
    (fp_text value "C_4u7_0603" (at 0 1.6) (layer "F.Fab")
        (effects (font (size 0.65 0.65) (thickness 0.13)) (justify right bottom))
    )
    (fp_text user "License: Apache-2.0" (at -1.682 5.895) (layer "F.Fab") hide
        (effects (font (size 0.7 0.7) (thickness 0.15)) (justify right bottom))
    )
    (fp_text user "Author: Antmicro" (at -1.682 4.894) (layer "F.Fab") hide
        (effects (font (size 0.7 0.7) (thickness 0.15)) (justify right bottom))
    )
    (fp_text user "${REFERENCE}" (at -1.682 3.895) (layer "F.Fab") hide
        (effects (font (size 0.7 0.7) (thickness 0.15)) (justify right bottom))
    )
    (fp_line (start -0.15 -0.4) (end 0.15 -0.4)
      (stroke (width 0.15) (type solid)) (layer "F.SilkS"))
    (fp_line (start -0.15 0.4) (end 0.15 0.4)
      (stroke (width 0.15) (type solid)) (layer "F.SilkS"))
    (fp_rect (start -1.25 -0.65) (end 1.25 0.65)
      (stroke (width 0.05) (type solid)) (fill none) (layer "F.CrtYd"))
    (fp_rect (start -0.8 -0.4) (end 0.8 0.4)
      (stroke (width 0.15) (type solid)) (fill none) (layer "F.Fab"))
    (pad "1" smd roundrect (at -0.7 0 180) (size 0.8 1) (layers "F.Cu" "F.Paste" "F.Mask") (roundrect_rratio 0.2)
      (net 2 "GND") (pintype "passive"))
    (pad "2" smd roundrect (at 0.7 0 180) (size 0.8 1) (layers "F.Cu" "F.Paste" "F.Mask") (roundrect_rratio 0.2)
      (net 32 "Net-(U4B-AVDD25)") (pintype "passive"))
  )
)
